# BASEBOARD_FAB2 (Tioga Pass) — schematic netlist excerpt (pin names and nets, part order shuffled) for the footprints in the layout excerpt that follows; sources: Cadence DE-HDL packaged netlist, KiCad conversion of Wiwynn_Tioga_Pass_MB.brd

C6A6  CAP  10UF 4V 20% X6S  pkg 0603LF  page 232 : A = PVPP_DEF ; B = GND
C25W9  CAP_A  0.1UF 16V 10% X7R  pkg 0402V  page 147 : A = P3V3_STBY_BMC_ADCVREFP ; B = P3V3_STBY_BMC_ADCVREFN
R8F8  RES  33.2 1% CHIP  pkg 0402  page 153 : A = SPI_SWITCH_CLK ; B = SPI_CLK_R0

(kicad_pcb
	(version 20260206)
	(generator "pcbnew")
	(generator_version "10.0")
	(general
		(thickness 1.6)
		(legacy_teardrops no)
	)
	(paper "A4")
	(title_block
		(title "Wiwynn_Tioga_Pass_MB.brd")
		(comment 1 "Tioga Pass / footprints 1475-1477 of 4770")
	)
	(layers
		(0 "F.Cu" signal "TOP")
		(4 "In1.Cu" signal "L2GND")
		(6 "In2.Cu" signal "L3")
		(8 "In3.Cu" signal "L4GND")
		(10 "In4.Cu" signal "L5")
		(12 "In5.Cu" signal "L6GND")
		(14 "In6.Cu" signal "L7VCC")
		(16 "In7.Cu" signal "L8VCC")
		(18 "In8.Cu" signal "L9GND")
		(20 "In9.Cu" signal "L10")
		(22 "In10.Cu" signal "L11GND")
		(24 "In11.Cu" signal "L12")
		(26 "In12.Cu" signal "L13GND")
		(2 "B.Cu" signal "BOTTOM")
		(9 "F.Adhes" user "F.Adhesive")
		(11 "B.Adhes" user "B.Adhesive")
		(13 "F.Paste" user "Package Geometry/Pastemask Top")
		(15 "B.Paste" user "Package Geometry/Pastemask Bottom")
		(5 "F.SilkS" user "Ref Des/Silkscreen Top")
		(7 "B.SilkS" user "Ref Des/Silkscreen Bottom")
		(1 "F.Mask" user "Board Geometry/Soldermask Top")
		(3 "B.Mask" user "Board Geometry/Soldermask Bottom")
		(17 "Dwgs.User" user "User.Drawings")
		(19 "Cmts.User" user "User.Comments")
		(21 "Eco1.User" user "User.Eco1")
		(23 "Eco2.User" user "User.Eco2")
		(25 "Edge.Cuts" user "Board Geometry/Outline")
		(27 "Margin" user)
		(31 "F.CrtYd" user "Package Geometry/Place Bound Top")
		(29 "B.CrtYd" user "Package Geometry/Place Bound Bottom")
		(35 "F.Fab" user "Ref Des/Assembly Top")
		(33 "B.Fab" user "Ref Des/Assembly Bottom")
	)
	(footprint ""
		(layer "F.Cu")
		(at 410.997146 -22.996652 90)
		(property "Reference" "C25W9"
			(at -0.8382 -0.67818 90)
			(unlocked yes)
			(layer "F.SilkS")
			(effects
				(font
					(size 0.4064 0.254)
					(thickness 0.1524)
				)
				(justify left)
			)
		)
		(property "Value" ""
			(at 0 0 90)
			(layer "F.Fab")
			(effects
				(font
					(size 1.27 1.27)
				)
			)
		)
		(duplicate_pad_numbers_are_jumpers no)
		(fp_poly
			(pts
				(xy 0.3048 -0.1016) (xy 0.3048 0.9906) (xy -0.3048 0.9906) (xy -0.3048 -0.1016)
			)
			(stroke
				(width 0)
				(type default)
			)
			(fill no)
			(layer "F.CrtYd")
		)
		(fp_line
			(start 0.3048 -0.1016)
			(end -0.3048 -0.1016)
			(stroke
				(width 0.1)
				(type default)
			)
			(layer "F.Fab")
		)
		(fp_line
			(start -0.3048 -0.1016)
			(end -0.3048 0.9906)
			(stroke
				(width 0.1)
				(type default)
			)
			(layer "F.Fab")
		)
		(fp_line
			(start 0.3048 0.9906)
			(end 0.3048 -0.1016)
			(stroke
				(width 0.1)
				(type default)
			)
			(layer "F.Fab")
		)
		(fp_line
			(start -0.3048 0.9906)
			(end 0.3048 0.9906)
			(stroke
				(width 0.1)
				(type default)
			)
			(layer "F.Fab")
		)
		(pad "1" smd rect
			(at 0 0 90)
			(size 0.508 0.508)
			(layers "F.Cu" "F.Mask" "F.Paste")
			(net "P3V3_STBY_BMC_ADCVREFP")
		)
		(pad "2" smd rect
			(at 0 0.889 90)
			(size 0.508 0.508)
			(layers "F.Cu" "F.Mask" "F.Paste")
			(net "P3V3_STBY_BMC_ADCVREFN")
		)
		(zone
			(layer "F.Cu")
			(hatch none 0.5)
			(connect_pads
				(clearance 0)
			)
			(min_thickness 0.25)
			(keepout
				(tracks allowed)
				(vias not_allowed)
				(pads allowed)
				(copperpour not_allowed)
				(footprints allowed)
			)
			(placement
				(enabled no)
				(sheetname "")
			)
			(fill
				(thermal_gap 0.5)
				(thermal_bridge_width 0.5)
				(island_removal_mode 0)
			)
			(polygon
				(pts
					(xy 411.251146 -22.742652) (xy 411.251146 -23.250652) (xy 411.632146 -23.250652) (xy 411.632146 -22.742652)
				)
			)
		)
		(zone
			(layer "F.Cu")
			(hatch none 0.5)
			(connect_pads
				(clearance 0)
			)
			(min_thickness 0.25)
			(keepout
				(tracks not_allowed)
				(vias allowed)
				(pads allowed)
				(copperpour not_allowed)
				(footprints allowed)
			)
			(placement
				(enabled no)
				(sheetname "")
			)
			(fill
				(thermal_gap 0.5)
				(thermal_bridge_width 0.5)
				(island_removal_mode 0)
			)
			(polygon
				(pts
					(xy 411.632146 -22.742652) (xy 411.632146 -23.250652) (xy 411.251146 -23.250652) (xy 411.251146 -22.742652)
				)
			)
		)
	)
	(footprint ""
		(layer "F.Cu")
		(at 385.2164 -50.8508 90)
		(property "Reference" "R8F8"
			(at 0 0 90)
			(layer "F.SilkS")
			(hide yes)
			(effects
				(font
					(size 1.27 1.27)
				)
			)
		)
		(property "Value" ""
			(at 0 0 90)
			(layer "F.Fab")
			(effects
				(font
					(size 1.27 1.27)
				)
			)
		)
		(duplicate_pad_numbers_are_jumpers no)
		(fp_poly
			(pts
				(xy -0.2794 -0.1016) (xy 0.2794 -0.1016) (xy 0.2794 0.9906) (xy -0.2794 0.9906)
			)
			(stroke
				(width 0)
				(type default)
			)
			(fill no)
			(layer "F.CrtYd")
		)
		(fp_line
			(start 0.2794 -0.1016)
			(end -0.2794 -0.1016)
			(stroke
				(width 0.1)
				(type default)
			)
			(layer "F.Fab")
		)
		(fp_line
			(start -0.2794 -0.1016)
			(end -0.2794 0.9906)
			(stroke
				(width 0.1)
				(type default)
			)
			(layer "F.Fab")
		)
		(fp_line
			(start 0.2794 0.9906)
			(end 0.2794 -0.1016)
			(stroke
				(width 0.1)
				(type default)
			)
			(layer "F.Fab")
		)
		(fp_line
			(start -0.2794 0.9906)
			(end 0.2794 0.9906)
			(stroke
				(width 0.1)
				(type default)
			)
			(layer "F.Fab")
		)
		(pad "1" smd rect
			(at 0 0 90)
			(size 0.508 0.508)
			(layers "F.Cu" "F.Mask" "F.Paste")
			(net "SPI_SWITCH_CLK")
		)
		(pad "2" smd rect
			(at 0 0.889 90)
			(size 0.508 0.508)
			(layers "F.Cu" "F.Mask" "F.Paste")
			(net "SPI_CLK_R0")
		)
		(zone
			(layer "F.Cu")
			(hatch none 0.5)
			(connect_pads
				(clearance 0)
			)
			(min_thickness 0.25)
			(keepout
				(tracks allowed)
				(vias not_allowed)
				(pads allowed)
				(copperpour not_allowed)
				(footprints allowed)
			)
			(placement
				(enabled no)
				(sheetname "")
			)
			(fill
				(thermal_gap 0.5)
				(thermal_bridge_width 0.5)
				(island_removal_mode 0)
			)
			(polygon
				(pts
					(xy 385.4704 -50.5968) (xy 385.4704 -51.1048) (xy 385.8514 -51.1048) (xy 385.8514 -50.5968)
				)
			)
		)
		(zone
			(layer "F.Cu")
			(hatch none 0.5)
			(connect_pads
				(clearance 0)
			)
			(min_thickness 0.25)
			(keepout
				(tracks not_allowed)
				(vias allowed)
				(pads allowed)
				(copperpour not_allowed)
				(footprints allowed)
			)
			(placement
				(enabled no)
				(sheetname "")
			)
			(fill
				(thermal_gap 0.5)
				(thermal_bridge_width 0.5)
				(island_removal_mode 0)
			)
			(polygon
				(pts
					(xy 385.8514 -50.5968) (xy 385.8514 -51.1048) (xy 385.4704 -51.1048) (xy 385.4704 -50.5968)
				)
			)
		)
	)
	(footprint ""
		(layer "F.Cu")
		(at 318.543432 -140.208 -90)
		(property "Reference" "C6A6"
			(at 0 0 270)
			(layer "F.SilkS")
			(hide yes)
			(effects
				(font
					(size 1.27 1.27)
				)
			)
		)
		(property "Value" ""
			(at 0 0 270)
			(layer "F.Fab")
			(effects
				(font
					(size 1.27 1.27)
				)
			)
		)
		(duplicate_pad_numbers_are_jumpers no)
		(fp_poly
			(pts
				(xy -0.4953 -0.2032) (xy 0.4953 -0.2032) (xy 0.4953 1.6002) (xy -0.4953 1.6002)
			)
			(stroke
				(width 0)
				(type default)
			)
			(fill no)
			(layer "F.CrtYd")
		)
		(fp_line
			(start -0.4953 1.6002)
			(end -0.4953 -0.2032)
			(stroke
				(width 0.1)
				(type default)
			)
			(layer "F.Fab")
		)
		(fp_line
			(start 0.4953 1.6002)
			(end -0.4953 1.6002)
			(stroke
				(width 0.1)
				(type default)
			)
			(layer "F.Fab")
		)
		(fp_line
			(start -0.4953 -0.2032)
			(end 0.4953 -0.2032)
			(stroke
				(width 0.1)
				(type default)
			)
			(layer "F.Fab")
		)
		(fp_line
			(start 0.4953 -0.2032)
			(end 0.4953 1.6002)
			(stroke
				(width 0.1)
				(type default)
			)
			(layer "F.Fab")
		)
		(pad "1" smd rect
			(at 0 0 270)
			(size 0.762 0.889)
			(layers "F.Cu" "F.Mask" "F.Paste")
			(net "PVPP_DEF")
		)
		(pad "2" smd rect
			(at 0 1.397 270)
			(size 0.762 0.889)
			(layers "F.Cu" "F.Mask" "F.Paste")
			(net "GND")
		)
		(zone
			(layer "F.Cu")
			(hatch none 0.5)
			(connect_pads
				(clearance 0)
			)
			(min_thickness 0.25)
			(keepout
				(tracks not_allowed)
				(vias allowed)
				(pads allowed)
				(copperpour not_allowed)
				(footprints allowed)
			)
			(placement
				(enabled no)
				(sheetname "")
			)
			(fill
				(thermal_gap 0.5)
				(thermal_bridge_width 0.5)
				(island_removal_mode 0)
			)
			(polygon
				(pts
					(xy 318.098932 -140.589) (xy 318.098932 -139.827) (xy 317.590932 -139.827) (xy 317.590932 -140.589)
				)
			)
		)
	)
)
